(kicad_pcb
	(version 20241229)
	(generator "pcbnew")
	(generator_version "9.0")
	(general
		(thickness 1.6642)
		(legacy_teardrops no)
	)
	(paper "A3")
	(title_block
		(title "PolarFire SoM")
		(date "2025-07-22")
		(rev "1.1.4")
		(company "Antmicro Ltd")
		(comment 1 "www.antmicro.com")
		(comment 9 "footprint 35 of 470 (U16), pads 62-80 of 80")
	)
	(layers
		(0 "F.Cu" mixed)
		(4 "In1.Cu" power)
		(6 "In2.Cu" signal)
		(8 "In3.Cu" power)
		(10 "In4.Cu" signal)
		(12 "In5.Cu" power)
		(14 "In6.Cu" power)
		(16 "In7.Cu" signal)
		(18 "In8.Cu" power)
		(20 "In9.Cu" signal)
		(22 "In10.Cu" power)
		(24 "In11.Cu" signal)
		(26 "In12.Cu" signal)
		(2 "B.Cu" mixed)
		(9 "F.Adhes" user "F.Adhesive")
		(11 "B.Adhes" user "B.Adhesive")
		(13 "F.Paste" user)
		(15 "B.Paste" user)
		(5 "F.SilkS" user "F.Silkscreen")
		(7 "B.SilkS" user "B.Silkscreen")
		(1 "F.Mask" user)
		(3 "B.Mask" user)
		(17 "Dwgs.User" user "User.Drawings")
		(19 "Cmts.User" user "User.Comments")
		(21 "Eco1.User" user "User.Eco1")
		(23 "Eco2.User" user "User.Eco2")
		(25 "Edge.Cuts" user)
		(27 "Margin" user)
		(31 "F.CrtYd" user "F.Courtyard")
		(29 "B.CrtYd" user "B.Courtyard")
		(35 "F.Fab" user)
		(33 "B.Fab" user)
	)
	(footprint "antmicro-footprints:BGA-80_7x7mm_Layout10x10_P0.65mm"
		(layer "F.Cu")
		(at 203.374 147.076 180)
		(property "Reference" "U16"
			(at 1.564 -4.684 0)
			(layer "F.SilkS")
			(effects
				(font
					(size 0.7 0.7)
					(thickness 0.15)
				)
				(justify right bottom)
			)
		)
		(property "Value" "CrossLink_LIF-MD6000-6JMG80I"
			(at 0 4.65 0)
			(layer "F.Fab")
			(hide yes)
			(effects
				(font
					(size 0.7 0.7)
					(thickness 0.15)
				)
				(justify right bottom)
			)
		)
		(property "Datasheet" "https://www.latticesemi.com/view_document?document_id=51662"
			(at 0 0 180)
			(layer "F.Fab")
			(hide yes)
			(effects
				(font
					(size 1.27 1.27)
					(thickness 0.15)
				)
			)
		)
		(property "Description" "FPGA, CrossLink, PLL37 I/O, 400 MHz, 5936 Cells, 1.14 V to 1.26 V, CTFBGA-80"
			(at 0 0 180)
			(layer "F.Fab")
			(hide yes)
			(effects
				(font
					(size 1.27 1.27)
					(thickness 0.15)
				)
			)
		)
		(property "Author" "Antmicro"
			(at 406.748 294.152 0)
			(layer "F.Fab")
			(hide yes)
			(effects
				(font
					(size 1 1)
					(thickness 0.15)
				)
			)
		)
		(property "License" "Apache-2.0"
			(at 406.748 294.152 0)
			(layer "F.Fab")
			(hide yes)
			(effects
				(font
					(size 1 1)
					(thickness 0.15)
				)
			)
		)
		(property "MPN" "LIF-MD6000-6JMG80I"
			(at 406.748 294.152 0)
			(layer "F.Fab")
			(hide yes)
			(effects
				(font
					(size 1 1)
					(thickness 0.15)
				)
			)
		)
		(property "Manufacturer" "Lattice Semiconductor"
			(at 406.748 294.152 0)
			(layer "F.Fab")
			(hide yes)
			(effects
				(font
					(size 1 1)
					(thickness 0.15)
				)
			)
		)
		(sheetname "/MIPI CrossLink/")
		(sheetfile "crosslink.kicad_sch")
		(attr smd)
		(pad "J2" smd circle
			(at -2.275 2.275 180)
			(size 0.35 0.35)
			(layers "F.Cu" "F.Mask" "F.Paste")
			(net 332 "Net-(U16-PB49{slash}PMU_WKUPN{slash}CDONE)")
			(pinfunction "PB49/PMU_WKUPN/CDONE")
			(pintype "passive")
			(solder_mask_margin -0.025)
			(solder_paste_margin -0.025)
		)
		(pad "J3" smd circle
			(at -1.625 2.275 180)
			(size 0.35 0.35)
			(layers "F.Cu" "F.Mask" "F.Paste")
			(net 299 "/FPGA HSIO/Crosslink_B1.D3")
			(pinfunction "PB43D")
			(pintype "bidirectional")
			(solder_mask_margin -0.025)
			(solder_paste_margin -0.025)
		)
		(pad "J4" smd circle
			(at -0.975 2.275 180)
			(size 0.35 0.35)
			(layers "F.Cu" "F.Mask" "F.Paste")
			(net 298 "/FPGA HSIO/Crosslink_B1.D2")
			(pinfunction "PB38D")
			(pintype "bidirectional")
			(solder_mask_margin -0.025)
			(solder_paste_margin -0.025)
		)
		(pad "J5" smd circle
			(at -0.325 2.275 180)
			(size 0.35 0.35)
			(layers "F.Cu" "F.Mask" "F.Paste")
			(net 300 "/FPGA HSIO/Crosslink_B1.D1")
			(pinfunction "PB34D/MIPI_CLKC1_0")
			(pintype "bidirectional")
			(solder_mask_margin -0.025)
			(solder_paste_margin -0.025)
		)
		(pad "J6" smd circle
			(at 0.325 2.275 180)
			(size 0.35 0.35)
			(layers "F.Cu" "F.Mask" "F.Paste")
			(net 303 "/FPGA HSIO/Crosslink_B1.D0")
			(pinfunction "PB29D/PCLKC1_1")
			(pintype "bidirectional")
			(solder_mask_margin -0.025)
			(solder_paste_margin -0.025)
		)
		(pad "J7" smd circle
			(at 0.975 2.275 180)
			(size 0.35 0.35)
			(layers "F.Cu" "F.Mask" "F.Paste")
			(net 340 "/FPGA HSIO/Crosslink_B1.PCLK")
			(pinfunction "PB29A/PCLKT1_0")
			(pintype "bidirectional")
			(solder_mask_margin -0.025)
			(solder_paste_margin -0.025)
		)
		(pad "J8" smd circle
			(at 1.625 2.275 180)
			(size 0.35 0.35)
			(layers "F.Cu" "F.Mask" "F.Paste")
			(net 210 "/FPGA HSIO/Crosslink_B2.D3")
			(pinfunction "PB16D/PCLKC2_1")
			(pintype "bidirectional")
			(solder_mask_margin -0.025)
			(solder_paste_margin -0.025)
		)
		(pad "J9" smd circle
			(at 2.275 2.275 180)
			(size 0.35 0.35)
			(layers "F.Cu" "F.Mask" "F.Paste")
			(net 136 "/FPGA HSIO/Crosslink_B2.D5")
			(pinfunction "PB6D")
			(pintype "bidirectional")
			(solder_mask_margin -0.025)
			(solder_paste_margin -0.025)
		)
		(pad "J10" smd circle
			(at 2.925 2.275 180)
			(size 0.35 0.35)
			(layers "F.Cu" "F.Mask" "F.Paste")
			(net 130 "/FPGA HSIO/Crosslink_B2.D6")
			(pinfunction "PB6C")
			(pintype "bidirectional")
			(solder_mask_margin -0.025)
			(solder_paste_margin -0.025)
		)
		(pad "K1" smd circle
			(at -2.925 2.925 180)
			(size 0.35 0.35)
			(layers "F.Cu" "F.Mask" "F.Paste")
			(net 563 "/FPGA GPIO/Crosslink.MISO")
			(pinfunction "PB51/MISO")
			(pintype "bidirectional")
			(solder_mask_margin -0.025)
			(solder_paste_margin -0.025)
		)
		(pad "K2" smd circle
			(at -2.275 2.925 180)
			(size 0.35 0.35)
			(layers "F.Cu" "F.Mask" "F.Paste")
			(net 537 "/FPGA GPIO/Crosslink.SDA")
			(pinfunction "PB47/PCLKT0_0/USER_SDA")
			(pintype "bidirectional")
			(solder_mask_margin -0.025)
			(solder_paste_margin -0.025)
		)
		(pad "K3" smd circle
			(at -1.625 2.925 180)
			(size 0.35 0.35)
			(layers "F.Cu" "F.Mask" "F.Paste")
			(net 291 "/FPGA HSIO/Crosslink_B1.D9")
			(pinfunction "PB43C")
			(pintype "bidirectional")
			(solder_mask_margin -0.025)
			(solder_paste_margin -0.025)
		)
		(pad "K4" smd circle
			(at -0.975 2.925 180)
			(size 0.35 0.35)
			(layers "F.Cu" "F.Mask" "F.Paste")
			(net 292 "/FPGA HSIO/Crosslink_B1.D8")
			(pinfunction "PB38C")
			(pintype "bidirectional")
			(solder_mask_margin -0.025)
			(solder_paste_margin -0.025)
		)
		(pad "K5" smd circle
			(at -0.325 2.925 180)
			(size 0.35 0.35)
			(layers "F.Cu" "F.Mask" "F.Paste")
			(net 293 "/FPGA HSIO/Crosslink_B1.D7")
			(pinfunction "PB34C/MIPI_CLKT1_0")
			(pintype "bidirectional")
			(solder_mask_margin -0.025)
			(solder_paste_margin -0.025)
		)
		(pad "K6" smd circle
			(at 0.325 2.925 180)
			(size 0.35 0.35)
			(layers "F.Cu" "F.Mask" "F.Paste")
			(net 328 "/FPGA HSIO/Crosslink_B1.D6")
			(pinfunction "PB29C/PCLKT1_1")
			(pintype "bidirectional")
			(solder_mask_margin -0.025)
			(solder_paste_margin -0.025)
		)
		(pad "K7" smd circle
			(at 0.975 2.925 180)
			(size 0.35 0.35)
			(layers "F.Cu" "F.Mask" "F.Paste")
			(net 337 "/FPGA HSIO/Crosslink_B1.D5")
			(pinfunction "PB29B/PCLKC1_0")
			(pintype "bidirectional")
			(solder_mask_margin -0.025)
			(solder_paste_margin -0.025)
		)
		(pad "K8" smd circle
			(at 1.625 2.925 180)
			(size 0.35 0.35)
			(layers "F.Cu" "F.Mask" "F.Paste")
			(net 304 "/FPGA HSIO/Crosslink_B2.D7")
			(pinfunction "PB16C/PCLKT2_1")
			(pintype "bidirectional")
			(solder_mask_margin -0.025)
			(solder_paste_margin -0.025)
		)
		(pad "K9" smd circle
			(at 2.275 2.925 180)
			(size 0.35 0.35)
			(layers "F.Cu" "F.Mask" "F.Paste")
			(net 294 "/FPGA HSIO/Crosslink_B2.D8")
			(pinfunction "PB12D")
			(pintype "bidirectional")
			(solder_mask_margin -0.025)
			(solder_paste_margin -0.025)
		)
		(pad "K10" smd circle
			(at 2.925 2.925 180)
			(size 0.35 0.35)
			(layers "F.Cu" "F.Mask" "F.Paste")
			(net 145 "/FPGA HSIO/Crosslink_B2.D9")
			(pinfunction "PB12C")
			(pintype "bidirectional")
			(solder_mask_margin -0.025)
			(solder_paste_margin -0.025)
		)
	)
)
